# S9S_MB_2U (Grand Teton) — schematic netlist excerpt (pin names and nets, part order shuffled) for the footprints in the layout excerpt that follows; sources: Cadence DE-HDL packaged netlist, KiCad conversion of 03242023_DA0F0TMBIJ0_F0T_Motherboard_J_brd_V01_OCP.brd

C295  Q_CAP  22UF 4V 20% X6S  pkg C0402  page 77 : A = PVCCIN_CPU1 ; B = GND
PC1877  Q_CAP  47PF 50V 5% NPO  pkg 0402  page 258 : A = P5V_AUX_FB ; B = P5V_AUX

(kicad_pcb
	(version 20260206)
	(generator "pcbnew")
	(generator_version "10.0")
	(general
		(thickness 1.6)
		(legacy_teardrops no)
	)
	(paper "A4")
	(title_block
		(title "03242023_DA0F0TMBIJ0_F0T_Motherboard_J_brd_V01_OCP.brd")
		(comment 1 "Grand Teton / footprints 3256-3257 of 6105")
	)
	(layers
		(0 "F.Cu" signal "TOP")
		(4 "In1.Cu" signal "GND")
		(6 "In2.Cu" signal "IN1")
		(8 "In3.Cu" signal "GND1")
		(10 "In4.Cu" signal "IN2")
		(12 "In5.Cu" signal "GND2")
		(14 "In6.Cu" signal "IN3")
		(16 "In7.Cu" signal "GND3")
		(18 "In8.Cu" signal "VCC")
		(20 "In9.Cu" signal "VCC1")
		(22 "In10.Cu" signal "GND4")
		(24 "In11.Cu" signal "IN4")
		(26 "In12.Cu" signal "GND5")
		(28 "In13.Cu" signal "IN5")
		(30 "In14.Cu" signal "GND6")
		(32 "In15.Cu" signal "IN6")
		(34 "In16.Cu" signal "GND7")
		(2 "B.Cu" signal "BOTTOM")
		(9 "F.Adhes" user "F.Adhesive")
		(11 "B.Adhes" user "B.Adhesive")
		(13 "F.Paste" user "Package Geometry/Pastemask Top")
		(15 "B.Paste" user "Package Geometry/Pastemask Bottom")
		(5 "F.SilkS" user "Ref Des/Silkscreen Top")
		(7 "B.SilkS" user "Ref Des/Silkscreen Bottom")
		(1 "F.Mask" user "Board Geometry/Soldermask Top")
		(3 "B.Mask" user "Board Geometry/Soldermask Bottom")
		(17 "Dwgs.User" user "User.Drawings")
		(19 "Cmts.User" user "User.Comments")
		(21 "Eco1.User" user "User.Eco1")
		(23 "Eco2.User" user "User.Eco2")
		(25 "Edge.Cuts" user "Board Geometry/Outline")
		(27 "Margin" user)
		(31 "F.CrtYd" user "Package Geometry/Place Bound Top")
		(29 "B.CrtYd" user "Package Geometry/Place Bound Bottom")
		(35 "F.Fab" user "Ref Des/Assembly Top")
		(33 "B.Fab" user "Ref Des/Assembly Bottom")
	)
	(footprint ""
		(layer "F.Cu")
		(at 107.307634 -247.715278 90)
		(property "Reference" "C295"
			(at 0 0 90)
			(layer "F.SilkS")
			(hide yes)
			(effects
				(font
					(size 1.27 1.27)
				)
			)
		)
		(property "Value" ""
			(at 0 0 90)
			(layer "F.Fab")
			(effects
				(font
					(size 1.27 1.27)
				)
			)
		)
		(duplicate_pad_numbers_are_jumpers no)
		(fp_line
			(start 0.7874 -0.4064)
			(end 0.7874 0.4064)
			(stroke
				(width 0.1524)
				(type default)
			)
			(layer "F.SilkS")
		)
		(fp_line
			(start -0.7874 -0.4064)
			(end 0.7874 -0.4064)
			(stroke
				(width 0.1524)
				(type default)
			)
			(layer "F.SilkS")
		)
		(fp_line
			(start 0.7874 0.4064)
			(end -0.7874 0.4064)
			(stroke
				(width 0.1524)
				(type default)
			)
			(layer "F.SilkS")
		)
		(fp_line
			(start -0.7874 0.4064)
			(end -0.7874 -0.4064)
			(stroke
				(width 0.1524)
				(type default)
			)
			(layer "F.SilkS")
		)
		(fp_line
			(start -0.12065 -0.305054)
			(end -0.12065 -0.2794)
			(stroke
				(width 0.1)
				(type default)
			)
			(layer "F.Fab")
		)
		(fp_line
			(start -0.67945 -0.305054)
			(end -0.12065 -0.305054)
			(stroke
				(width 0.1)
				(type default)
			)
			(layer "F.Fab")
		)
		(fp_line
			(start 0.67945 -0.3048)
			(end 0.67945 0.3048)
			(stroke
				(width 0.1)
				(type default)
			)
			(layer "F.Fab")
		)
		(fp_line
			(start 0.12065 -0.3048)
			(end 0.67945 -0.3048)
			(stroke
				(width 0.1)
				(type default)
			)
			(layer "F.Fab")
		)
		(fp_line
			(start 0.12065 -0.2794)
			(end 0.12065 -0.3048)
			(stroke
				(width 0.1)
				(type default)
			)
			(layer "F.Fab")
		)
		(fp_line
			(start -0.12065 -0.2794)
			(end 0.12065 -0.2794)
			(stroke
				(width 0.1)
				(type default)
			)
			(layer "F.Fab")
		)
		(fp_line
			(start 0.120396 0.2794)
			(end -0.12065 0.2794)
			(stroke
				(width 0.1)
				(type default)
			)
			(layer "F.Fab")
		)
		(fp_line
			(start -0.12065 0.2794)
			(end -0.12065 0.3048)
			(stroke
				(width 0.1)
				(type default)
			)
			(layer "F.Fab")
		)
		(fp_line
			(start 0.67945 0.3048)
			(end 0.120396 0.3048)
			(stroke
				(width 0.1)
				(type default)
			)
			(layer "F.Fab")
		)
		(fp_line
			(start 0.120396 0.3048)
			(end 0.120396 0.2794)
			(stroke
				(width 0.1)
				(type default)
			)
			(layer "F.Fab")
		)
		(fp_line
			(start -0.12065 0.3048)
			(end -0.67945 0.3048)
			(stroke
				(width 0.1)
				(type default)
			)
			(layer "F.Fab")
		)
		(fp_line
			(start -0.67945 0.3048)
			(end -0.67945 -0.305054)
			(stroke
				(width 0.1)
				(type default)
			)
			(layer "F.Fab")
		)
		(pad "1" smd circle
			(at -0.40005 0 90)
			(size 0 0)
			(layers "F.Cu" "F.Mask" "F.Paste")
			(net "PVCCIN_CPU1")
		)
		(pad "2" smd circle
			(at 0.40005 0 90)
			(size 0 0)
			(layers "F.Cu" "F.Mask" "F.Paste")
			(net "GND")
		)
	)
	(footprint ""
		(layer "F.Cu")
		(at 459.267814 -379.556772)
		(property "Reference" "PC1877"
			(at 0 0 0)
			(layer "F.SilkS")
			(hide yes)
			(effects
				(font
					(size 1.27 1.27)
				)
			)
		)
		(property "Value" ""
			(at 0 0 0)
			(layer "F.Fab")
			(effects
				(font
					(size 1.27 1.27)
				)
			)
		)
		(duplicate_pad_numbers_are_jumpers no)
		(fp_line
			(start -0.7874 -0.4064)
			(end 0.7874 -0.4064)
			(stroke
				(width 0.1524)
				(type default)
			)
			(layer "F.SilkS")
		)
		(fp_line
			(start -0.7874 0.4064)
			(end -0.7874 -0.4064)
			(stroke
				(width 0.1524)
				(type default)
			)
			(layer "F.SilkS")
		)
		(fp_line
			(start 0.7874 -0.4064)
			(end 0.7874 0.4064)
			(stroke
				(width 0.1524)
				(type default)
			)
			(layer "F.SilkS")
		)
		(fp_line
			(start 0.7874 0.4064)
			(end -0.7874 0.4064)
			(stroke
				(width 0.1524)
				(type default)
			)
			(layer "F.SilkS")
		)
		(fp_line
			(start -0.67945 -0.305054)
			(end -0.12065 -0.305054)
			(stroke
				(width 0.1)
				(type default)
			)
			(layer "F.Fab")
		)
		(fp_line
			(start -0.67945 0.3048)
			(end -0.67945 -0.305054)
			(stroke
				(width 0.1)
				(type default)
			)
			(layer "F.Fab")
		)
		(fp_line
			(start -0.12065 -0.305054)
			(end -0.12065 -0.2794)
			(stroke
				(width 0.1)
				(type default)
			)
			(layer "F.Fab")
		)
		(fp_line
			(start -0.12065 -0.2794)
			(end 0.12065 -0.2794)
			(stroke
				(width 0.1)
				(type default)
			)
			(layer "F.Fab")
		)
		(fp_line
			(start -0.12065 0.2794)
			(end -0.12065 0.3048)
			(stroke
				(width 0.1)
				(type default)
			)
			(layer "F.Fab")
		)
		(fp_line
			(start -0.12065 0.3048)
			(end -0.67945 0.3048)
			(stroke
				(width 0.1)
				(type default)
			)
			(layer "F.Fab")
		)
		(fp_line
			(start 0.120396 0.2794)
			(end -0.12065 0.2794)
			(stroke
				(width 0.1)
				(type default)
			)
			(layer "F.Fab")
		)
		(fp_line
			(start 0.120396 0.3048)
			(end 0.120396 0.2794)
			(stroke
				(width 0.1)
				(type default)
			)
			(layer "F.Fab")
		)
		(fp_line
			(start 0.12065 -0.3048)
			(end 0.67945 -0.3048)
			(stroke
				(width 0.1)
				(type default)
			)
			(layer "F.Fab")
		)
		(fp_line
			(start 0.12065 -0.2794)
			(end 0.12065 -0.3048)
			(stroke
				(width 0.1)
				(type default)
			)
			(layer "F.Fab")
		)
		(fp_line
			(start 0.67945 -0.3048)
			(end 0.67945 0.3048)
			(stroke
				(width 0.1)
				(type default)
			)
			(layer "F.Fab")
		)
		(fp_line
			(start 0.67945 0.3048)
			(end 0.120396 0.3048)
			(stroke
				(width 0.1)
				(type default)
			)
			(layer "F.Fab")
		)
		(pad "1" smd circle
			(at -0.40005 0)
			(size 0 0)
			(layers "F.Cu" "F.Mask" "F.Paste")
			(net "P5V_AUX_FB")
		)
		(pad "2" smd circle
			(at 0.40005 0)
			(size 0 0)
			(layers "F.Cu" "F.Mask" "F.Paste")
			(net "P5V_AUX")
		)
	)
)
